# SCM (Grand Teton) — schematic netlist excerpt (pin names and nets, part order shuffled) for the footprints in the layout excerpt that follows; sources: Cadence DE-HDL packaged netlist, KiCad conversion of 12092022_DA0F0TMDCD0_F0T_Management_Board_D_brd_V3_OCP.brd

R259  Q_RES  2.2K 5% CHIP  pkg 0402LF  page 27 : A = P3V3_AUX ; B = SMB_BMC_MM8_SDA

(kicad_pcb
	(version 20260206)
	(generator "pcbnew")
	(generator_version "10.0")
	(general
		(thickness 1.6)
		(legacy_teardrops no)
	)
	(paper "A4")
	(title_block
		(title "12092022_DA0F0TMDCD0_F0T_Management_Board_D_brd_V3_OCP.brd")
		(comment 1 "Grand Teton / footprints 1301-1301 of 1440")
	)
	(layers
		(0 "F.Cu" signal "TOP")
		(4 "In1.Cu" signal "GND")
		(6 "In2.Cu" signal "IN1")
		(8 "In3.Cu" signal "GND1")
		(10 "In4.Cu" signal "IN2")
		(12 "In5.Cu" signal "VCC")
		(14 "In6.Cu" signal "VCC1")
		(16 "In7.Cu" signal "IN3")
		(18 "In8.Cu" signal "GND2")
		(20 "In9.Cu" signal "IN4")
		(22 "In10.Cu" signal "GND3")
		(2 "B.Cu" signal "BOTTOM")
		(9 "F.Adhes" user "F.Adhesive")
		(11 "B.Adhes" user "B.Adhesive")
		(13 "F.Paste" user "Package Geometry/Pastemask Top")
		(15 "B.Paste" user "Package Geometry/Pastemask Bottom")
		(5 "F.SilkS" user "Ref Des/Silkscreen Top")
		(7 "B.SilkS" user "Ref Des/Silkscreen Bottom")
		(1 "F.Mask" user "Board Geometry/Soldermask Top")
		(3 "B.Mask" user "Board Geometry/Soldermask Bottom")
		(17 "Dwgs.User" user "User.Drawings")
		(19 "Cmts.User" user "User.Comments")
		(21 "Eco1.User" user "User.Eco1")
		(23 "Eco2.User" user "User.Eco2")
		(25 "Edge.Cuts" user "Board Geometry/Outline")
		(27 "Margin" user)
		(31 "F.CrtYd" user "Package Geometry/Place Bound Top")
		(29 "B.CrtYd" user "Package Geometry/Place Bound Bottom")
		(35 "F.Fab" user "Ref Des/Assembly Top")
		(33 "B.Fab" user "Ref Des/Assembly Bottom")
	)
	(footprint ""
		(layer "B.Cu")
		(at 56.727852 -30.867604 -90)
		(property "Reference" "R259"
			(at 0 0 90)
			(layer "B.SilkS")
			(hide yes)
			(effects
				(font
					(size 1.27 1.27)
				)
				(justify mirror)
			)
		)
		(property "Value" ""
			(at 0 0 90)
			(layer "B.Fab")
			(effects
				(font
					(size 1.27 1.27)
				)
				(justify mirror)
			)
		)
		(duplicate_pad_numbers_are_jumpers no)
		(fp_line
			(start -0.7874 0.4064)
			(end 0.7874 0.4064)
			(stroke
				(width 0.1524)
				(type default)
			)
			(layer "B.SilkS")
		)
		(fp_line
			(start 0.7874 0.4064)
			(end 0.7874 -0.4064)
			(stroke
				(width 0.1524)
				(type default)
			)
			(layer "B.SilkS")
		)
		(fp_line
			(start -0.7874 -0.4064)
			(end -0.7874 0.4064)
			(stroke
				(width 0.1524)
				(type default)
			)
			(layer "B.SilkS")
		)
		(fp_line
			(start 0.7874 -0.4064)
			(end -0.7874 -0.4064)
			(stroke
				(width 0.1524)
				(type default)
			)
			(layer "B.SilkS")
		)
		(fp_line
			(start -0.67945 0.3048)
			(end -0.120396 0.3048)
			(stroke
				(width 0.1)
				(type default)
			)
			(layer "B.Fab")
		)
		(fp_line
			(start -0.120396 0.3048)
			(end -0.120396 0.2794)
			(stroke
				(width 0.1)
				(type default)
			)
			(layer "B.Fab")
		)
		(fp_line
			(start 0.12065 0.3048)
			(end 0.67945 0.3048)
			(stroke
				(width 0.1)
				(type default)
			)
			(layer "B.Fab")
		)
		(fp_line
			(start 0.67945 0.3048)
			(end 0.67945 -0.305054)
			(stroke
				(width 0.1)
				(type default)
			)
			(layer "B.Fab")
		)
		(fp_line
			(start -0.120396 0.2794)
			(end 0.12065 0.2794)
			(stroke
				(width 0.1)
				(type default)
			)
			(layer "B.Fab")
		)
		(fp_line
			(start 0.12065 0.2794)
			(end 0.12065 0.3048)
			(stroke
				(width 0.1)
				(type default)
			)
			(layer "B.Fab")
		)
		(fp_line
			(start -0.12065 -0.2794)
			(end -0.12065 -0.3048)
			(stroke
				(width 0.1)
				(type default)
			)
			(layer "B.Fab")
		)
		(fp_line
			(start 0.12065 -0.2794)
			(end -0.12065 -0.2794)
			(stroke
				(width 0.1)
				(type default)
			)
			(layer "B.Fab")
		)
		(fp_line
			(start -0.67945 -0.3048)
			(end -0.67945 0.3048)
			(stroke
				(width 0.1)
				(type default)
			)
			(layer "B.Fab")
		)
		(fp_line
			(start -0.12065 -0.3048)
			(end -0.67945 -0.3048)
			(stroke
				(width 0.1)
				(type default)
			)
			(layer "B.Fab")
		)
		(fp_line
			(start 0.12065 -0.305054)
			(end 0.12065 -0.2794)
			(stroke
				(width 0.1)
				(type default)
			)
			(layer "B.Fab")
		)
		(fp_line
			(start 0.67945 -0.305054)
			(end 0.12065 -0.305054)
			(stroke
				(width 0.1)
				(type default)
			)
			(layer "B.Fab")
		)
		(pad "1" smd circle
			(at 0.40005 0 90)
			(size 0 0)
			(layers "B.Cu" "B.Mask" "B.Paste")
			(net "P3V3_AUX")
		)
		(pad "2" smd circle
			(at -0.40005 0 90)
			(size 0 0)
			(layers "B.Cu" "B.Mask" "B.Paste")
			(net "SMB_BMC_MM8_SDA")
		)
	)
)
